# T6G (Grand Teton) — schematic netlist excerpt (pin names and nets, part order shuffled) for the footprints in the layout excerpt that follows; sources: Cadence DE-HDL packaged netlist, KiCad conversion of 04192023_DAF0TMB3IC0_F0TG_MB_C_brd_V02_OCP.brd

J85  PICOPROBE_BXA  DELTA-L 4.0 EMPTY  pkg TRIANG_LAUNCH_3PXB  page 229
  \1_p\  = DELTA_L_85_10INCH_IN3_DN
  \2_n\  = DELTA_L_85_10INCH_IN3_DP
  \3_g\  = DELTA_L_GND_1

(kicad_pcb
	(version 20260206)
	(generator "pcbnew")
	(generator_version "10.0")
	(general
		(thickness 1.6)
		(legacy_teardrops no)
	)
	(paper "A4")
	(title_block
		(title "04192023_DAF0TMB3IC0_F0TG_MB_C_brd_V02_OCP.brd")
		(comment 1 "Grand Teton / footprints 3485-3485 of 8354")
	)
	(layers
		(0 "F.Cu" signal "TOP")
		(4 "In1.Cu" signal "GND")
		(6 "In2.Cu" signal "IN1")
		(8 "In3.Cu" signal "GND1")
		(10 "In4.Cu" signal "IN2")
		(12 "In5.Cu" signal "GND2")
		(14 "In6.Cu" signal "IN3")
		(16 "In7.Cu" signal "GND3")
		(18 "In8.Cu" signal "VCC")
		(20 "In9.Cu" signal "VCC1")
		(22 "In10.Cu" signal "GND4")
		(24 "In11.Cu" signal "IN4")
		(26 "In12.Cu" signal "GND5")
		(28 "In13.Cu" signal "IN5")
		(30 "In14.Cu" signal "GND6")
		(32 "In15.Cu" signal "IN6")
		(34 "In16.Cu" signal "GND7")
		(2 "B.Cu" signal "BOTTOM")
		(9 "F.Adhes" user "F.Adhesive")
		(11 "B.Adhes" user "B.Adhesive")
		(13 "F.Paste" user "Package Geometry/Pastemask Top")
		(15 "B.Paste" user "Package Geometry/Pastemask Bottom")
		(5 "F.SilkS" user "Ref Des/Silkscreen Top")
		(7 "B.SilkS" user "Ref Des/Silkscreen Bottom")
		(1 "F.Mask" user "Board Geometry/Soldermask Top")
		(3 "B.Mask" user "Board Geometry/Soldermask Bottom")
		(17 "Dwgs.User" user "User.Drawings")
		(19 "Cmts.User" user "User.Comments")
		(21 "Eco1.User" user "User.Eco1")
		(23 "Eco2.User" user "User.Eco2")
		(25 "Edge.Cuts" user "Board Geometry/Outline")
		(27 "Margin" user)
		(31 "F.CrtYd" user "Package Geometry/Place Bound Top")
		(29 "B.CrtYd" user "Package Geometry/Place Bound Bottom")
		(35 "F.Fab" user "Ref Des/Assembly Top")
		(33 "B.Fab" user "Ref Des/Assembly Bottom")
	)
	(footprint ""
		(layer "F.Cu")
		(at 300.538388 5.082794 180)
		(property "Reference" "J85"
			(at -4.414774 -1.317498 90)
			(unlocked yes)
			(layer "F.SilkS")
			(effects
				(font
					(size 0.7874 0.5842)
					(thickness 0.1524)
				)
				(justify left)
			)
		)
		(property "Value" ""
			(at 0 0 180)
			(layer "F.Fab")
			(effects
				(font
					(size 1.27 1.27)
				)
			)
		)
		(duplicate_pad_numbers_are_jumpers no)
		(fp_line
			(start 1.2192 2.06756)
			(end -1.2192 2.06756)
			(stroke
				(width 0.1524)
				(type default)
			)
			(layer "F.SilkS")
		)
		(fp_line
			(start 1.2192 -2.06756)
			(end 1.2192 2.06756)
			(stroke
				(width 0.1524)
				(type default)
			)
			(layer "F.SilkS")
		)
		(fp_line
			(start -1.2192 2.06756)
			(end -1.2192 -2.06756)
			(stroke
				(width 0.1524)
				(type default)
			)
			(layer "F.SilkS")
		)
		(fp_line
			(start -1.2192 -2.06756)
			(end 1.2192 -2.06756)
			(stroke
				(width 0.1524)
				(type default)
			)
			(layer "F.SilkS")
		)
		(pad "" np_thru_hole circle
			(at -2.8829 -1.27 90)
			(size 1.0414 1.0414)
			(drill 1.0414)
			(layers "*.Cu" "*.Mask")
			(clearance 0.381)
			(thermal_gap 0.381)
		)
		(pad "" np_thru_hole circle
			(at -2.8829 1.27 90)
			(size 1.0414 1.0414)
			(drill 1.0414)
			(layers "*.Cu" "*.Mask")
			(clearance 0.381)
			(thermal_gap 0.381)
		)
		(pad "" np_thru_hole circle
			(at 3.4671 -1.27 90)
			(size 1.0414 1.0414)
			(drill 1.0414)
			(layers "*.Cu" "*.Mask")
			(clearance 0.381)
			(thermal_gap 0.381)
		)
		(pad "" np_thru_hole circle
			(at 3.4671 1.27 90)
			(size 1.0414 1.0414)
			(drill 1.0414)
			(layers "*.Cu" "*.Mask")
			(clearance 0.381)
			(thermal_gap 0.381)
		)
		(pad "1" smd rect
			(at 0.8255 -0.249936 90)
			(size 0.3048 0.508)
			(layers "F.Cu" "F.Mask" "F.Paste")
			(net "DELTA_L_85_10INCH_IN3_DN")
		)
		(pad "2" smd rect
			(at 0.8255 0.249936 90)
			(size 0.3048 0.508)
			(layers "F.Cu" "F.Mask" "F.Paste")
			(net "DELTA_L_85_10INCH_IN3_DP")
		)
		(pad "3" smd circle
			(at 0 0 180)
			(size 0 0)
			(layers "F.Cu" "F.Mask" "F.Paste")
			(net "DELTA_L_GND_1")
		)
		(zone
			(layer "F.Cu")
			(hatch none 0.5)
			(connect_pads
				(clearance 0)
			)
			(min_thickness 0.25)
			(keepout
				(tracks not_allowed)
				(vias allowed)
				(pads allowed)
				(copperpour not_allowed)
				(footprints allowed)
			)
			(placement
				(enabled no)
				(sheetname "")
			)
			(fill
				(thermal_gap 0.5)
				(thermal_bridge_width 0.5)
				(island_removal_mode 0)
			)
			(polygon
				(pts
					(xy 299.420788 5.631434) (xy 299.420788 5.53593) (xy 300.017688 5.53593) (xy 300.017688 5.12953)
					(xy 299.420788 5.12953) (xy 299.420788 5.036058) (xy 300.017688 5.036058) (xy 300.017688 4.629658)
					(xy 299.420788 4.629658) (xy 299.420788 4.534154) (xy 300.119288 4.534154) (xy 300.119288 5.631434)
				)
			)
		)
		(zone
			(layers "F.Cu" "B.Cu" "In1.Cu" "In2.Cu" "In3.Cu" "In4.Cu" "In5.Cu" "In6.Cu"
				"In7.Cu" "In8.Cu" "In9.Cu" "In10.Cu" "In11.Cu" "In12.Cu" "In13.Cu" "In14.Cu"
				"In15.Cu" "In16.Cu"
			)
			(hatch none 0.5)
			(connect_pads
				(clearance 0)
			)
			(min_thickness 0.25)
			(keepout
				(tracks not_allowed)
				(vias allowed)
				(pads allowed)
				(copperpour not_allowed)
				(footprints allowed)
			)
			(placement
				(enabled no)
				(sheetname "")
			)
			(fill
				(thermal_gap 0.5)
				(thermal_bridge_width 0.5)
				(island_removal_mode 0)
			)
			(polygon
				(pts
					(arc
						(start 297.998388 3.812794)
						(mid 296.144188 3.812794)
						(end 297.998388 3.812794)
					)
				)
			)
		)
		(zone
			(layers "F.Cu" "B.Cu" "In1.Cu" "In2.Cu" "In3.Cu" "In4.Cu" "In5.Cu" "In6.Cu"
				"In7.Cu" "In8.Cu" "In9.Cu" "In10.Cu" "In11.Cu" "In12.Cu" "In13.Cu" "In14.Cu"
				"In15.Cu" "In16.Cu"
			)
			(hatch none 0.5)
			(connect_pads
				(clearance 0)
			)
			(min_thickness 0.25)
			(keepout
				(tracks not_allowed)
				(vias allowed)
				(pads allowed)
				(copperpour not_allowed)
				(footprints allowed)
			)
			(placement
				(enabled no)
				(sheetname "")
			)
			(fill
				(thermal_gap 0.5)
				(thermal_bridge_width 0.5)
				(island_removal_mode 0)
			)
			(polygon
				(pts
					(arc
						(start 297.998388 6.352794)
						(mid 296.144188 6.352794)
						(end 297.998388 6.352794)
					)
				)
			)
		)
		(zone
			(layers "F.Cu" "B.Cu" "In1.Cu" "In2.Cu" "In3.Cu" "In4.Cu" "In5.Cu" "In6.Cu"
				"In7.Cu" "In8.Cu" "In9.Cu" "In10.Cu" "In11.Cu" "In12.Cu" "In13.Cu" "In14.Cu"
				"In15.Cu" "In16.Cu"
			)
			(hatch none 0.5)
			(connect_pads
				(clearance 0)
			)
			(min_thickness 0.25)
			(keepout
				(tracks not_allowed)
				(vias allowed)
				(pads allowed)
				(copperpour not_allowed)
				(footprints allowed)
			)
			(placement
				(enabled no)
				(sheetname "")
			)
			(fill
				(thermal_gap 0.5)
				(thermal_bridge_width 0.5)
				(island_removal_mode 0)
			)
			(polygon
				(pts
					(arc
						(start 304.348388 3.812794)
						(mid 302.494188 3.812794)
						(end 304.348388 3.812794)
					)
				)
			)
		)
		(zone
			(layers "F.Cu" "B.Cu" "In1.Cu" "In2.Cu" "In3.Cu" "In4.Cu" "In5.Cu" "In6.Cu"
				"In7.Cu" "In8.Cu" "In9.Cu" "In10.Cu" "In11.Cu" "In12.Cu" "In13.Cu" "In14.Cu"
				"In15.Cu" "In16.Cu"
			)
			(hatch none 0.5)
			(connect_pads
				(clearance 0)
			)
			(min_thickness 0.25)
			(keepout
				(tracks not_allowed)
				(vias allowed)
				(pads allowed)
				(copperpour not_allowed)
				(footprints allowed)
			)
			(placement
				(enabled no)
				(sheetname "")
			)
			(fill
				(thermal_gap 0.5)
				(thermal_bridge_width 0.5)
				(island_removal_mode 0)
			)
			(polygon
				(pts
					(arc
						(start 304.348388 6.352794)
						(mid 302.494188 6.352794)
						(end 304.348388 6.352794)
					)
				)
			)
		)
	)
)
